# T6G (Grand Teton) — schematic netlist excerpt (pin names and nets, part order shuffled) for the footprints in the layout excerpt that follows; sources: Cadence DE-HDL packaged netlist, KiCad conversion of 04192023_DAF0TMB3IC0_F0TG_MB_C_brd_V02_OCP.brd

R6226  Q_RES  10K 1% EMPTY  pkg 0402LF  page 176 : A = P3V3_AUX ; B = SMB_USB_CPU0_HUB1_SCL_R2
C6755  Q_CAP_DIFFBUS  DIFF BUS_0.22UF 6.3V 20% X6S  pkg C0201  page 352 : \1\ = P5E_CPU1_P3_TX_BUF_C_DP<15> ; \2\ = P5E_CPU1_P3_TX_BUF_DP<15>
R900  Q_RES  0 5% CHIP  pkg 0603LF  page 356 : A = P0V9_CPU1_RT3_2A_2D ; B = P0V9_CPU1_RT3_2A

(kicad_pcb
	(version 20260206)
	(generator "pcbnew")
	(generator_version "10.0")
	(general
		(thickness 1.6)
		(legacy_teardrops no)
	)
	(paper "A4")
	(title_block
		(title "04192023_DAF0TMB3IC0_F0TG_MB_C_brd_V02_OCP.brd")
		(comment 1 "Grand Teton / footprints 6961-6963 of 8354")
	)
	(layers
		(0 "F.Cu" signal "TOP")
		(4 "In1.Cu" signal "GND")
		(6 "In2.Cu" signal "IN1")
		(8 "In3.Cu" signal "GND1")
		(10 "In4.Cu" signal "IN2")
		(12 "In5.Cu" signal "GND2")
		(14 "In6.Cu" signal "IN3")
		(16 "In7.Cu" signal "GND3")
		(18 "In8.Cu" signal "VCC")
		(20 "In9.Cu" signal "VCC1")
		(22 "In10.Cu" signal "GND4")
		(24 "In11.Cu" signal "IN4")
		(26 "In12.Cu" signal "GND5")
		(28 "In13.Cu" signal "IN5")
		(30 "In14.Cu" signal "GND6")
		(32 "In15.Cu" signal "IN6")
		(34 "In16.Cu" signal "GND7")
		(2 "B.Cu" signal "BOTTOM")
		(9 "F.Adhes" user "F.Adhesive")
		(11 "B.Adhes" user "B.Adhesive")
		(13 "F.Paste" user "Package Geometry/Pastemask Top")
		(15 "B.Paste" user "Package Geometry/Pastemask Bottom")
		(5 "F.SilkS" user "Ref Des/Silkscreen Top")
		(7 "B.SilkS" user "Ref Des/Silkscreen Bottom")
		(1 "F.Mask" user "Board Geometry/Soldermask Top")
		(3 "B.Mask" user "Board Geometry/Soldermask Bottom")
		(17 "Dwgs.User" user "User.Drawings")
		(19 "Cmts.User" user "User.Comments")
		(21 "Eco1.User" user "User.Eco1")
		(23 "Eco2.User" user "User.Eco2")
		(25 "Edge.Cuts" user "Board Geometry/Outline")
		(27 "Margin" user)
		(31 "F.CrtYd" user "Package Geometry/Place Bound Top")
		(29 "B.CrtYd" user "Package Geometry/Place Bound Bottom")
		(35 "F.Fab" user "Ref Des/Assembly Top")
		(33 "B.Fab" user "Ref Des/Assembly Bottom")
	)
	(footprint ""
		(layer "B.Cu")
		(at 108.46181 -393.242546 180)
		(property "Reference" "R900"
			(at 0 0 0)
			(layer "B.SilkS")
			(hide yes)
			(effects
				(font
					(size 1.27 1.27)
				)
				(justify mirror)
			)
		)
		(property "Value" ""
			(at 0 0 0)
			(layer "B.Fab")
			(effects
				(font
					(size 1.27 1.27)
				)
				(justify mirror)
			)
		)
		(duplicate_pad_numbers_are_jumpers no)
		(fp_line
			(start 1.2954 0.5842)
			(end 1.2954 -0.5842)
			(stroke
				(width 0.1524)
				(type default)
			)
			(layer "B.SilkS")
		)
		(fp_line
			(start 1.2954 -0.5842)
			(end -1.2954 -0.5842)
			(stroke
				(width 0.1524)
				(type default)
			)
			(layer "B.SilkS")
		)
		(fp_line
			(start -1.2954 0.5842)
			(end 1.2954 0.5842)
			(stroke
				(width 0.1524)
				(type default)
			)
			(layer "B.SilkS")
		)
		(fp_line
			(start -1.2954 -0.5842)
			(end -1.2954 0.5842)
			(stroke
				(width 0.1524)
				(type default)
			)
			(layer "B.SilkS")
		)
		(fp_line
			(start 1.1938 0.4064)
			(end 1.1938 -0.406654)
			(stroke
				(width 0.1)
				(type default)
			)
			(layer "B.Fab")
		)
		(fp_line
			(start 1.1938 -0.406654)
			(end 0.8636 -0.406654)
			(stroke
				(width 0.1)
				(type default)
			)
			(layer "B.Fab")
		)
		(fp_line
			(start 0.8636 0.4572)
			(end 0.8636 0.4318)
			(stroke
				(width 0.1)
				(type default)
			)
			(layer "B.Fab")
		)
		(fp_line
			(start 0.8636 0.4318)
			(end 0.8636 0.4064)
			(stroke
				(width 0.1)
				(type default)
			)
			(layer "B.Fab")
		)
		(fp_line
			(start 0.8636 0.4064)
			(end 1.1938 0.4064)
			(stroke
				(width 0.1)
				(type default)
			)
			(layer "B.Fab")
		)
		(fp_line
			(start 0.8636 -0.406654)
			(end 0.8636 -0.4572)
			(stroke
				(width 0.1)
				(type default)
			)
			(layer "B.Fab")
		)
		(fp_line
			(start 0.8636 -0.4572)
			(end -0.8636 -0.4572)
			(stroke
				(width 0.1)
				(type default)
			)
			(layer "B.Fab")
		)
		(fp_line
			(start -0.8636 0.4572)
			(end 0.8636 0.4572)
			(stroke
				(width 0.1)
				(type default)
			)
			(layer "B.Fab")
		)
		(fp_line
			(start -0.8636 0.4064)
			(end -0.8636 0.4572)
			(stroke
				(width 0.1)
				(type default)
			)
			(layer "B.Fab")
		)
		(fp_line
			(start -0.8636 -0.406654)
			(end -1.1938 -0.406654)
			(stroke
				(width 0.1)
				(type default)
			)
			(layer "B.Fab")
		)
		(fp_line
			(start -0.8636 -0.4572)
			(end -0.8636 -0.406654)
			(stroke
				(width 0.1)
				(type default)
			)
			(layer "B.Fab")
		)
		(fp_line
			(start -1.1938 0.4064)
			(end -0.8636 0.4064)
			(stroke
				(width 0.1)
				(type default)
			)
			(layer "B.Fab")
		)
		(fp_line
			(start -1.1938 -0.406654)
			(end -1.1938 0.4064)
			(stroke
				(width 0.1)
				(type default)
			)
			(layer "B.Fab")
		)
		(pad "1" smd rect
			(at 0.7366 0 90)
			(size 0.7112 0.8128)
			(layers "B.Cu" "B.Mask" "B.Paste")
			(net "P0V9_CPU1_RT3_2A_2D")
		)
		(pad "2" smd rect
			(at -0.7366 0 90)
			(size 0.7112 0.8128)
			(layers "B.Cu" "B.Mask" "B.Paste")
			(net "P0V9_CPU1_RT3_2A")
		)
	)
	(footprint ""
		(layer "B.Cu")
		(at 112.19434 -62.01791 -90)
		(property "Reference" "R6226"
			(at 0 0 90)
			(layer "B.SilkS")
			(hide yes)
			(effects
				(font
					(size 1.27 1.27)
				)
				(justify mirror)
			)
		)
		(property "Value" ""
			(at 0 0 90)
			(layer "B.Fab")
			(effects
				(font
					(size 1.27 1.27)
				)
				(justify mirror)
			)
		)
		(duplicate_pad_numbers_are_jumpers no)
		(fp_line
			(start -0.7874 0.4064)
			(end 0.7874 0.4064)
			(stroke
				(width 0.1524)
				(type default)
			)
			(layer "B.SilkS")
		)
		(fp_line
			(start 0.7874 0.4064)
			(end 0.7874 -0.4064)
			(stroke
				(width 0.1524)
				(type default)
			)
			(layer "B.SilkS")
		)
		(fp_line
			(start -0.7874 -0.4064)
			(end -0.7874 0.4064)
			(stroke
				(width 0.1524)
				(type default)
			)
			(layer "B.SilkS")
		)
		(fp_line
			(start 0.7874 -0.4064)
			(end -0.7874 -0.4064)
			(stroke
				(width 0.1524)
				(type default)
			)
			(layer "B.SilkS")
		)
		(fp_line
			(start -0.67945 0.3048)
			(end -0.120396 0.3048)
			(stroke
				(width 0.1)
				(type default)
			)
			(layer "B.Fab")
		)
		(fp_line
			(start -0.120396 0.3048)
			(end -0.120396 0.2794)
			(stroke
				(width 0.1)
				(type default)
			)
			(layer "B.Fab")
		)
		(fp_line
			(start 0.12065 0.3048)
			(end 0.67945 0.3048)
			(stroke
				(width 0.1)
				(type default)
			)
			(layer "B.Fab")
		)
		(fp_line
			(start 0.67945 0.3048)
			(end 0.67945 -0.305054)
			(stroke
				(width 0.1)
				(type default)
			)
			(layer "B.Fab")
		)
		(fp_line
			(start -0.120396 0.2794)
			(end 0.12065 0.2794)
			(stroke
				(width 0.1)
				(type default)
			)
			(layer "B.Fab")
		)
		(fp_line
			(start 0.12065 0.2794)
			(end 0.12065 0.3048)
			(stroke
				(width 0.1)
				(type default)
			)
			(layer "B.Fab")
		)
		(fp_line
			(start -0.12065 -0.2794)
			(end -0.12065 -0.3048)
			(stroke
				(width 0.1)
				(type default)
			)
			(layer "B.Fab")
		)
		(fp_line
			(start 0.12065 -0.2794)
			(end -0.12065 -0.2794)
			(stroke
				(width 0.1)
				(type default)
			)
			(layer "B.Fab")
		)
		(fp_line
			(start -0.67945 -0.3048)
			(end -0.67945 0.3048)
			(stroke
				(width 0.1)
				(type default)
			)
			(layer "B.Fab")
		)
		(fp_line
			(start -0.12065 -0.3048)
			(end -0.67945 -0.3048)
			(stroke
				(width 0.1)
				(type default)
			)
			(layer "B.Fab")
		)
		(fp_line
			(start 0.12065 -0.305054)
			(end 0.12065 -0.2794)
			(stroke
				(width 0.1)
				(type default)
			)
			(layer "B.Fab")
		)
		(fp_line
			(start 0.67945 -0.305054)
			(end 0.12065 -0.305054)
			(stroke
				(width 0.1)
				(type default)
			)
			(layer "B.Fab")
		)
		(pad "1" smd circle
			(at 0.40005 0 90)
			(size 0 0)
			(layers "B.Cu" "B.Mask" "B.Paste")
			(net "P3V3_AUX")
		)
		(pad "2" smd circle
			(at -0.40005 0 90)
			(size 0 0)
			(layers "B.Cu" "B.Mask" "B.Paste")
			(net "SMB_USB_CPU0_HUB1_SCL_R2")
		)
	)
	(footprint ""
		(layer "B.Cu")
		(at 163.263326 -408.517344 90)
		(property "Reference" "C6755"
			(at 0 0 90)
			(layer "B.SilkS")
			(hide yes)
			(effects
				(font
					(size 1.27 1.27)
				)
				(justify mirror)
			)
		)
		(property "Value" ""
			(at 0 0 90)
			(layer "B.Fab")
			(effects
				(font
					(size 1.27 1.27)
				)
				(justify mirror)
			)
		)
		(duplicate_pad_numbers_are_jumpers no)
		(fp_line
			(start 0.299974 -0.150114)
			(end -0.299974 -0.150114)
			(stroke
				(width 0.1)
				(type default)
			)
			(layer "B.Fab")
		)
		(fp_line
			(start -0.299974 -0.150114)
			(end -0.299974 0.150114)
			(stroke
				(width 0.1)
				(type default)
			)
			(layer "B.Fab")
		)
		(fp_line
			(start 0.299974 0.150114)
			(end 0.299974 -0.150114)
			(stroke
				(width 0.1)
				(type default)
			)
			(layer "B.Fab")
		)
		(fp_line
			(start -0.299974 0.150114)
			(end 0.299974 0.150114)
			(stroke
				(width 0.1)
				(type default)
			)
			(layer "B.Fab")
		)
		(pad "1" smd rect
			(at 0.2667 0 270)
			(size 0.3048 0.381)
			(layers "B.Cu" "B.Mask" "B.Paste")
			(net "P5E_CPU1_P3_TX_BUF_C_DP<15>")
		)
		(pad "2" smd rect
			(at -0.2667 0 270)
			(size 0.3048 0.381)
			(layers "B.Cu" "B.Mask" "B.Paste")
			(net "P5E_CPU1_P3_TX_BUF_DP<15>")
		)
	)
)
